# T6G (Grand Teton) — schematic netlist excerpt (pin names and nets, part order shuffled) for the footprints in the layout excerpt that follows; sources: Cadence DE-HDL packaged netlist, KiCad conversion of 04192023_DAF0TMB3IC0_F0TG_MB_C_brd_V02_OCP.brd

R247  Q_RES  33 5% CHIP  pkg 0402LF  page 27 : A = APML_CPU0_ALERT_N ; B = APML_CPU0_ALERT_R_N
PC8567  Q_CAP  22UF 16V 20% X6S  pkg C0805  page 190 : A = SW_P3V3_AUX_FLT ; B = GND
PR258  Q_RES  5.6 1% CHIP  pkg 0402LF  page 218 : A = SW_PVDDCR_CPU1_P1_BOOT1 ; B = SW_PVDDCR_CPU1_P1_BOOT1_R

(kicad_pcb
	(version 20260206)
	(generator "pcbnew")
	(generator_version "10.0")
	(general
		(thickness 1.6)
		(legacy_teardrops no)
	)
	(paper "A4")
	(title_block
		(title "04192023_DAF0TMB3IC0_F0TG_MB_C_brd_V02_OCP.brd")
		(comment 1 "Grand Teton / footprints 4547-4549 of 8354")
	)
	(layers
		(0 "F.Cu" signal "TOP")
		(4 "In1.Cu" signal "GND")
		(6 "In2.Cu" signal "IN1")
		(8 "In3.Cu" signal "GND1")
		(10 "In4.Cu" signal "IN2")
		(12 "In5.Cu" signal "GND2")
		(14 "In6.Cu" signal "IN3")
		(16 "In7.Cu" signal "GND3")
		(18 "In8.Cu" signal "VCC")
		(20 "In9.Cu" signal "VCC1")
		(22 "In10.Cu" signal "GND4")
		(24 "In11.Cu" signal "IN4")
		(26 "In12.Cu" signal "GND5")
		(28 "In13.Cu" signal "IN5")
		(30 "In14.Cu" signal "GND6")
		(32 "In15.Cu" signal "IN6")
		(34 "In16.Cu" signal "GND7")
		(2 "B.Cu" signal "BOTTOM")
		(9 "F.Adhes" user "F.Adhesive")
		(11 "B.Adhes" user "B.Adhesive")
		(13 "F.Paste" user "Package Geometry/Pastemask Top")
		(15 "B.Paste" user "Package Geometry/Pastemask Bottom")
		(5 "F.SilkS" user "Ref Des/Silkscreen Top")
		(7 "B.SilkS" user "Ref Des/Silkscreen Bottom")
		(1 "F.Mask" user "Board Geometry/Soldermask Top")
		(3 "B.Mask" user "Board Geometry/Soldermask Bottom")
		(17 "Dwgs.User" user "User.Drawings")
		(19 "Cmts.User" user "User.Comments")
		(21 "Eco1.User" user "User.Eco1")
		(23 "Eco2.User" user "User.Eco2")
		(25 "Edge.Cuts" user "Board Geometry/Outline")
		(27 "Margin" user)
		(31 "F.CrtYd" user "Package Geometry/Place Bound Top")
		(29 "B.CrtYd" user "Package Geometry/Place Bound Bottom")
		(35 "F.Fab" user "Ref Des/Assembly Top")
		(33 "B.Fab" user "Ref Des/Assembly Bottom")
	)
	(footprint ""
		(layer "F.Cu")
		(at 449.795392 -52.84851 90)
		(property "Reference" "PC8567"
			(at 0 0 90)
			(layer "F.SilkS")
			(hide yes)
			(effects
				(font
					(size 1.27 1.27)
				)
			)
		)
		(property "Value" ""
			(at 0 0 90)
			(layer "F.Fab")
			(effects
				(font
					(size 1.27 1.27)
				)
			)
		)
		(duplicate_pad_numbers_are_jumpers no)
		(fp_line
			(start 1.524 -0.762)
			(end 1.524 0.762)
			(stroke
				(width 0.1524)
				(type default)
			)
			(layer "F.SilkS")
		)
		(fp_line
			(start -1.524 -0.762)
			(end 1.524 -0.762)
			(stroke
				(width 0.1524)
				(type default)
			)
			(layer "F.SilkS")
		)
		(fp_line
			(start 1.524 0.762)
			(end -1.524 0.762)
			(stroke
				(width 0.1524)
				(type default)
			)
			(layer "F.SilkS")
		)
		(fp_line
			(start -1.524 0.762)
			(end -1.524 -0.762)
			(stroke
				(width 0.1524)
				(type default)
			)
			(layer "F.SilkS")
		)
		(fp_line
			(start 1.1049 -0.724916)
			(end -1.1049 -0.724916)
			(stroke
				(width 0.1)
				(type default)
			)
			(layer "F.Fab")
		)
		(fp_line
			(start -1.1049 -0.724916)
			(end -1.1049 0.724916)
			(stroke
				(width 0.1)
				(type default)
			)
			(layer "F.Fab")
		)
		(fp_line
			(start 1.1049 0.724916)
			(end 1.1049 -0.724916)
			(stroke
				(width 0.1)
				(type default)
			)
			(layer "F.Fab")
		)
		(fp_line
			(start -1.1049 0.724916)
			(end 1.1049 0.724916)
			(stroke
				(width 0.1)
				(type default)
			)
			(layer "F.Fab")
		)
		(pad "1" smd rect
			(at -0.889 0 270)
			(size 1.016 1.27)
			(layers "F.Cu" "F.Mask" "F.Paste")
			(net "SW_P3V3_AUX_FLT")
		)
		(pad "2" smd rect
			(at 0.889 0 270)
			(size 1.016 1.27)
			(layers "F.Cu" "F.Mask" "F.Paste")
			(net "GND")
		)
	)
	(footprint ""
		(layer "F.Cu")
		(at 325.545958 -193.925952 -90)
		(property "Reference" "R247"
			(at 0 0 270)
			(layer "F.SilkS")
			(hide yes)
			(effects
				(font
					(size 1.27 1.27)
				)
			)
		)
		(property "Value" ""
			(at 0 0 270)
			(layer "F.Fab")
			(effects
				(font
					(size 1.27 1.27)
				)
			)
		)
		(duplicate_pad_numbers_are_jumpers no)
		(fp_line
			(start -0.7874 0.4064)
			(end -0.7874 -0.4064)
			(stroke
				(width 0.1524)
				(type default)
			)
			(layer "F.SilkS")
		)
		(fp_line
			(start 0.7874 0.4064)
			(end -0.7874 0.4064)
			(stroke
				(width 0.1524)
				(type default)
			)
			(layer "F.SilkS")
		)
		(fp_line
			(start -0.7874 -0.4064)
			(end 0.7874 -0.4064)
			(stroke
				(width 0.1524)
				(type default)
			)
			(layer "F.SilkS")
		)
		(fp_line
			(start 0.7874 -0.4064)
			(end 0.7874 0.4064)
			(stroke
				(width 0.1524)
				(type default)
			)
			(layer "F.SilkS")
		)
		(fp_line
			(start -0.67945 0.3048)
			(end -0.67945 -0.305054)
			(stroke
				(width 0.1)
				(type default)
			)
			(layer "F.Fab")
		)
		(fp_line
			(start -0.12065 0.3048)
			(end -0.67945 0.3048)
			(stroke
				(width 0.1)
				(type default)
			)
			(layer "F.Fab")
		)
		(fp_line
			(start 0.120396 0.3048)
			(end 0.120396 0.2794)
			(stroke
				(width 0.1)
				(type default)
			)
			(layer "F.Fab")
		)
		(fp_line
			(start 0.67945 0.3048)
			(end 0.120396 0.3048)
			(stroke
				(width 0.1)
				(type default)
			)
			(layer "F.Fab")
		)
		(fp_line
			(start -0.12065 0.2794)
			(end -0.12065 0.3048)
			(stroke
				(width 0.1)
				(type default)
			)
			(layer "F.Fab")
		)
		(fp_line
			(start 0.120396 0.2794)
			(end -0.12065 0.2794)
			(stroke
				(width 0.1)
				(type default)
			)
			(layer "F.Fab")
		)
		(fp_line
			(start -0.12065 -0.2794)
			(end 0.12065 -0.2794)
			(stroke
				(width 0.1)
				(type default)
			)
			(layer "F.Fab")
		)
		(fp_line
			(start 0.12065 -0.2794)
			(end 0.12065 -0.3048)
			(stroke
				(width 0.1)
				(type default)
			)
			(layer "F.Fab")
		)
		(fp_line
			(start 0.12065 -0.3048)
			(end 0.67945 -0.3048)
			(stroke
				(width 0.1)
				(type default)
			)
			(layer "F.Fab")
		)
		(fp_line
			(start 0.67945 -0.3048)
			(end 0.67945 0.3048)
			(stroke
				(width 0.1)
				(type default)
			)
			(layer "F.Fab")
		)
		(fp_line
			(start -0.67945 -0.305054)
			(end -0.12065 -0.305054)
			(stroke
				(width 0.1)
				(type default)
			)
			(layer "F.Fab")
		)
		(fp_line
			(start -0.12065 -0.305054)
			(end -0.12065 -0.2794)
			(stroke
				(width 0.1)
				(type default)
			)
			(layer "F.Fab")
		)
		(pad "1" smd circle
			(at -0.40005 0 270)
			(size 0 0)
			(layers "F.Cu" "F.Mask" "F.Paste")
			(net "APML_CPU0_ALERT_N")
		)
		(pad "2" smd circle
			(at 0.40005 0 270)
			(size 0 0)
			(layers "F.Cu" "F.Mask" "F.Paste")
			(net "APML_CPU0_ALERT_R_N")
		)
	)
	(footprint ""
		(layer "F.Cu")
		(at 87.88146 -339.630258 90)
		(property "Reference" "PR258"
			(at 0 0 90)
			(layer "F.SilkS")
			(hide yes)
			(effects
				(font
					(size 1.27 1.27)
				)
			)
		)
		(property "Value" ""
			(at 0 0 90)
			(layer "F.Fab")
			(effects
				(font
					(size 1.27 1.27)
				)
			)
		)
		(duplicate_pad_numbers_are_jumpers no)
		(fp_line
			(start 0.7874 -0.4064)
			(end 0.7874 0.4064)
			(stroke
				(width 0.1524)
				(type default)
			)
			(layer "F.SilkS")
		)
		(fp_line
			(start -0.7874 -0.4064)
			(end 0.7874 -0.4064)
			(stroke
				(width 0.1524)
				(type default)
			)
			(layer "F.SilkS")
		)
		(fp_line
			(start 0.7874 0.4064)
			(end -0.7874 0.4064)
			(stroke
				(width 0.1524)
				(type default)
			)
			(layer "F.SilkS")
		)
		(fp_line
			(start -0.7874 0.4064)
			(end -0.7874 -0.4064)
			(stroke
				(width 0.1524)
				(type default)
			)
			(layer "F.SilkS")
		)
		(fp_line
			(start -0.12065 -0.305054)
			(end -0.12065 -0.2794)
			(stroke
				(width 0.1)
				(type default)
			)
			(layer "F.Fab")
		)
		(fp_line
			(start -0.67945 -0.305054)
			(end -0.12065 -0.305054)
			(stroke
				(width 0.1)
				(type default)
			)
			(layer "F.Fab")
		)
		(fp_line
			(start 0.67945 -0.3048)
			(end 0.67945 0.3048)
			(stroke
				(width 0.1)
				(type default)
			)
			(layer "F.Fab")
		)
		(fp_line
			(start 0.12065 -0.3048)
			(end 0.67945 -0.3048)
			(stroke
				(width 0.1)
				(type default)
			)
			(layer "F.Fab")
		)
		(fp_line
			(start 0.12065 -0.2794)
			(end 0.12065 -0.3048)
			(stroke
				(width 0.1)
				(type default)
			)
			(layer "F.Fab")
		)
		(fp_line
			(start -0.12065 -0.2794)
			(end 0.12065 -0.2794)
			(stroke
				(width 0.1)
				(type default)
			)
			(layer "F.Fab")
		)
		(fp_line
			(start 0.120396 0.2794)
			(end -0.12065 0.2794)
			(stroke
				(width 0.1)
				(type default)
			)
			(layer "F.Fab")
		)
		(fp_line
			(start -0.12065 0.2794)
			(end -0.12065 0.3048)
			(stroke
				(width 0.1)
				(type default)
			)
			(layer "F.Fab")
		)
		(fp_line
			(start 0.67945 0.3048)
			(end 0.120396 0.3048)
			(stroke
				(width 0.1)
				(type default)
			)
			(layer "F.Fab")
		)
		(fp_line
			(start 0.120396 0.3048)
			(end 0.120396 0.2794)
			(stroke
				(width 0.1)
				(type default)
			)
			(layer "F.Fab")
		)
		(fp_line
			(start -0.12065 0.3048)
			(end -0.67945 0.3048)
			(stroke
				(width 0.1)
				(type default)
			)
			(layer "F.Fab")
		)
		(fp_line
			(start -0.67945 0.3048)
			(end -0.67945 -0.305054)
			(stroke
				(width 0.1)
				(type default)
			)
			(layer "F.Fab")
		)
		(pad "1" smd circle
			(at -0.40005 0 90)
			(size 0 0)
			(layers "F.Cu" "F.Mask" "F.Paste")
			(net "SW_PVDDCR_CPU1_P1_BOOT1")
		)
		(pad "2" smd circle
			(at 0.40005 0 90)
			(size 0 0)
			(layers "F.Cu" "F.Mask" "F.Paste")
			(net "SW_PVDDCR_CPU1_P1_BOOT1_R")
		)
	)
)
